# T6G (Grand Teton) — schematic netlist excerpt (pin names and nets, part order shuffled) for the footprints in the layout excerpt that follows; sources: Cadence DE-HDL packaged netlist, KiCad conversion of 04192023_DAF0TMB3IC0_F0TG_MB_C_brd_V02_OCP.brd

C2113  Q_CAP  22UF 4V 20% X6S  pkg C0402  page 74 : A = PVDD11_S3_P1 ; B = GND

Q124  MOSFET_NCH_DUAL  PJT138K IC  pkg SOT363XD  page 134
  S1  = GND
  G1  = P3V3_OCP_EN_1_R
  D2  = P3V3_OCP_UV_1_R1
  S2  = GND
  G2  = P3V3_OCP_1_EN_G
  D1  = P3V3_OCP_1_EN_G

(kicad_pcb
	(version 20260206)
	(generator "pcbnew")
	(generator_version "10.0")
	(general
		(thickness 1.6)
		(legacy_teardrops no)
	)
	(paper "A4")
	(title_block
		(title "04192023_DAF0TMB3IC0_F0TG_MB_C_brd_V02_OCP.brd")
		(comment 1 "Grand Teton / footprints 817-818 of 8354")
	)
	(layers
		(0 "F.Cu" signal "TOP")
		(4 "In1.Cu" signal "GND")
		(6 "In2.Cu" signal "IN1")
		(8 "In3.Cu" signal "GND1")
		(10 "In4.Cu" signal "IN2")
		(12 "In5.Cu" signal "GND2")
		(14 "In6.Cu" signal "IN3")
		(16 "In7.Cu" signal "GND3")
		(18 "In8.Cu" signal "VCC")
		(20 "In9.Cu" signal "VCC1")
		(22 "In10.Cu" signal "GND4")
		(24 "In11.Cu" signal "IN4")
		(26 "In12.Cu" signal "GND5")
		(28 "In13.Cu" signal "IN5")
		(30 "In14.Cu" signal "GND6")
		(32 "In15.Cu" signal "IN6")
		(34 "In16.Cu" signal "GND7")
		(2 "B.Cu" signal "BOTTOM")
		(9 "F.Adhes" user "F.Adhesive")
		(11 "B.Adhes" user "B.Adhesive")
		(13 "F.Paste" user "Package Geometry/Pastemask Top")
		(15 "B.Paste" user "Package Geometry/Pastemask Bottom")
		(5 "F.SilkS" user "Ref Des/Silkscreen Top")
		(7 "B.SilkS" user "Ref Des/Silkscreen Bottom")
		(1 "F.Mask" user "Board Geometry/Soldermask Top")
		(3 "B.Mask" user "Board Geometry/Soldermask Bottom")
		(17 "Dwgs.User" user "User.Drawings")
		(19 "Cmts.User" user "User.Comments")
		(21 "Eco1.User" user "User.Eco1")
		(23 "Eco2.User" user "User.Eco2")
		(25 "Edge.Cuts" user "Board Geometry/Outline")
		(27 "Margin" user)
		(31 "F.CrtYd" user "Package Geometry/Place Bound Top")
		(29 "B.CrtYd" user "Package Geometry/Place Bound Bottom")
		(35 "F.Fab" user "Ref Des/Assembly Top")
		(33 "B.Fab" user "Ref Des/Assembly Bottom")
	)
	(footprint ""
		(layer "F.Cu")
		(at 111.477044 -261.748016 -90)
		(property "Reference" "C2113"
			(at 0 0 270)
			(layer "F.SilkS")
			(hide yes)
			(effects
				(font
					(size 1.27 1.27)
				)
			)
		)
		(property "Value" ""
			(at 0 0 270)
			(layer "F.Fab")
			(effects
				(font
					(size 1.27 1.27)
				)
			)
		)
		(duplicate_pad_numbers_are_jumpers no)
		(fp_line
			(start -0.7874 0.4064)
			(end -0.7874 -0.4064)
			(stroke
				(width 0.1524)
				(type default)
			)
			(layer "F.SilkS")
		)
		(fp_line
			(start 0.7874 0.4064)
			(end -0.7874 0.4064)
			(stroke
				(width 0.1524)
				(type default)
			)
			(layer "F.SilkS")
		)
		(fp_line
			(start -0.7874 -0.4064)
			(end 0.7874 -0.4064)
			(stroke
				(width 0.1524)
				(type default)
			)
			(layer "F.SilkS")
		)
		(fp_line
			(start 0.7874 -0.4064)
			(end 0.7874 0.4064)
			(stroke
				(width 0.1524)
				(type default)
			)
			(layer "F.SilkS")
		)
		(fp_line
			(start -0.67945 0.3048)
			(end -0.67945 -0.305054)
			(stroke
				(width 0.1)
				(type default)
			)
			(layer "F.Fab")
		)
		(fp_line
			(start -0.12065 0.3048)
			(end -0.67945 0.3048)
			(stroke
				(width 0.1)
				(type default)
			)
			(layer "F.Fab")
		)
		(fp_line
			(start 0.120396 0.3048)
			(end 0.120396 0.2794)
			(stroke
				(width 0.1)
				(type default)
			)
			(layer "F.Fab")
		)
		(fp_line
			(start 0.67945 0.3048)
			(end 0.120396 0.3048)
			(stroke
				(width 0.1)
				(type default)
			)
			(layer "F.Fab")
		)
		(fp_line
			(start -0.12065 0.2794)
			(end -0.12065 0.3048)
			(stroke
				(width 0.1)
				(type default)
			)
			(layer "F.Fab")
		)
		(fp_line
			(start 0.120396 0.2794)
			(end -0.12065 0.2794)
			(stroke
				(width 0.1)
				(type default)
			)
			(layer "F.Fab")
		)
		(fp_line
			(start -0.12065 -0.2794)
			(end 0.12065 -0.2794)
			(stroke
				(width 0.1)
				(type default)
			)
			(layer "F.Fab")
		)
		(fp_line
			(start 0.12065 -0.2794)
			(end 0.12065 -0.3048)
			(stroke
				(width 0.1)
				(type default)
			)
			(layer "F.Fab")
		)
		(fp_line
			(start 0.12065 -0.3048)
			(end 0.67945 -0.3048)
			(stroke
				(width 0.1)
				(type default)
			)
			(layer "F.Fab")
		)
		(fp_line
			(start 0.67945 -0.3048)
			(end 0.67945 0.3048)
			(stroke
				(width 0.1)
				(type default)
			)
			(layer "F.Fab")
		)
		(fp_line
			(start -0.67945 -0.305054)
			(end -0.12065 -0.305054)
			(stroke
				(width 0.1)
				(type default)
			)
			(layer "F.Fab")
		)
		(fp_line
			(start -0.12065 -0.305054)
			(end -0.12065 -0.2794)
			(stroke
				(width 0.1)
				(type default)
			)
			(layer "F.Fab")
		)
		(pad "1" smd circle
			(at -0.40005 0 270)
			(size 0 0)
			(layers "F.Cu" "F.Mask" "F.Paste")
			(net "PVDD11_S3_P1")
		)
		(pad "2" smd circle
			(at 0.40005 0 270)
			(size 0 0)
			(layers "F.Cu" "F.Mask" "F.Paste")
			(net "GND")
		)
	)
	(footprint ""
		(layer "F.Cu")
		(at 458.80147 -41.105836)
		(property "Reference" "Q124"
			(at -2.899664 -2.731262 0)
			(unlocked yes)
			(layer "F.SilkS")
			(effects
				(font
					(size 0.7874 0.5842)
					(thickness 0.1524)
				)
				(justify left)
			)
		)
		(property "Value" ""
			(at 0 0 0)
			(layer "F.Fab")
			(effects
				(font
					(size 1.27 1.27)
				)
			)
		)
		(duplicate_pad_numbers_are_jumpers no)
		(fp_line
			(start -1.332738 -1.100074)
			(end -0.4826 -1.100074)
			(stroke
				(width 0.1524)
				(type default)
			)
			(layer "F.SilkS")
		)
		(fp_line
			(start -1.332738 1.100074)
			(end -1.332738 -1.100074)
			(stroke
				(width 0.1524)
				(type default)
			)
			(layer "F.SilkS")
		)
		(fp_line
			(start -0.4826 -1.100074)
			(end 0 -0.541274)
			(stroke
				(width 0.1524)
				(type default)
			)
			(layer "F.SilkS")
		)
		(fp_line
			(start 0 -0.541274)
			(end 0.4826 -1.100074)
			(stroke
				(width 0.1524)
				(type default)
			)
			(layer "F.SilkS")
		)
		(fp_line
			(start 0.4826 -1.100074)
			(end 1.332738 -1.100074)
			(stroke
				(width 0.1524)
				(type default)
			)
			(layer "F.SilkS")
		)
		(fp_line
			(start 1.332738 -1.100074)
			(end 1.332738 1.100074)
			(stroke
				(width 0.1524)
				(type default)
			)
			(layer "F.SilkS")
		)
		(fp_line
			(start 1.332738 1.100074)
			(end -1.332738 1.100074)
			(stroke
				(width 0.1524)
				(type default)
			)
			(layer "F.SilkS")
		)
		(fp_poly
			(pts
				(xy -1.489456 -1.189482) (xy -2.23393 -1.43764) (xy -1.737614 -1.933956)
			)
			(stroke
				(width 0)
				(type default)
			)
			(fill yes)
			(layer "F.SilkS")
		)
		(fp_line
			(start -0.674878 -1.100074)
			(end 0.674878 -1.100074)
			(stroke
				(width 0.1)
				(type default)
			)
			(layer "F.Fab")
		)
		(fp_line
			(start -0.674878 1.100074)
			(end -0.674878 -1.100074)
			(stroke
				(width 0.1)
				(type default)
			)
			(layer "F.Fab")
		)
		(fp_line
			(start 0.674878 -1.100074)
			(end 0.674878 1.100074)
			(stroke
				(width 0.1)
				(type default)
			)
			(layer "F.Fab")
		)
		(fp_line
			(start 0.674878 1.100074)
			(end -0.674878 1.100074)
			(stroke
				(width 0.1)
				(type default)
			)
			(layer "F.Fab")
		)
		(fp_poly
			(pts
				(xy -2.2352 -0.298958) (xy -2.2352 -1.001014) (xy -1.533144 -0.649986)
			)
			(stroke
				(width 0)
				(type default)
			)
			(fill yes)
			(layer "F.Fab")
		)
		(pad "1" smd rect
			(at -0.94996 -0.649986 90)
			(size 0.4318 0.508)
			(layers "F.Cu" "F.Mask" "F.Paste")
			(net "GND")
		)
		(pad "2" smd rect
			(at -0.94996 0 90)
			(size 0.4318 0.508)
			(layers "F.Cu" "F.Mask" "F.Paste")
			(net "P3V3_OCP_EN_1_R")
		)
		(pad "3" smd rect
			(at -0.94996 0.649986 90)
			(size 0.4318 0.508)
			(layers "F.Cu" "F.Mask" "F.Paste")
			(net "P3V3_OCP_UV_1_R1")
		)
		(pad "4" smd rect
			(at 0.94996 0.649986 90)
			(size 0.4318 0.508)
			(layers "F.Cu" "F.Mask" "F.Paste")
			(net "GND")
		)
		(pad "5" smd rect
			(at 0.94996 0 90)
			(size 0.4318 0.508)
			(layers "F.Cu" "F.Mask" "F.Paste")
			(net "P3V3_OCP_1_EN_G")
		)
		(pad "6" smd rect
			(at 0.94996 -0.649986 90)
			(size 0.4318 0.508)
			(layers "F.Cu" "F.Mask" "F.Paste")
			(net "P3V3_OCP_1_EN_G")
		)
	)
)
